# S9S_MB_2U (Grand Teton) — schematic netlist excerpt (pin names and nets, part order shuffled) for the footprints in the layout excerpt that follows; sources: Cadence DE-HDL packaged netlist, KiCad conversion of 03242023_DA0F0TMBIJ0_F0T_Motherboard_J_brd_V01_OCP.brd

R1469  Q_RES  33.2 1% CHIP  pkg 0402LF  page 223 : A = RST_PLTRST_PLD_B_N ; B = RST_PLTRST_B_N
R4712  Q_RES  100K 1% CHIP  pkg 0402LF  page 185 : A = RST_PFR_OVR_RTC ; B = GND

(kicad_pcb
	(version 20260206)
	(generator "pcbnew")
	(generator_version "10.0")
	(general
		(thickness 1.6)
		(legacy_teardrops no)
	)
	(paper "A4")
	(title_block
		(title "03242023_DA0F0TMBIJ0_F0T_Motherboard_J_brd_V01_OCP.brd")
		(comment 1 "Grand Teton / footprints 3737-3738 of 6105")
	)
	(layers
		(0 "F.Cu" signal "TOP")
		(4 "In1.Cu" signal "GND")
		(6 "In2.Cu" signal "IN1")
		(8 "In3.Cu" signal "GND1")
		(10 "In4.Cu" signal "IN2")
		(12 "In5.Cu" signal "GND2")
		(14 "In6.Cu" signal "IN3")
		(16 "In7.Cu" signal "GND3")
		(18 "In8.Cu" signal "VCC")
		(20 "In9.Cu" signal "VCC1")
		(22 "In10.Cu" signal "GND4")
		(24 "In11.Cu" signal "IN4")
		(26 "In12.Cu" signal "GND5")
		(28 "In13.Cu" signal "IN5")
		(30 "In14.Cu" signal "GND6")
		(32 "In15.Cu" signal "IN6")
		(34 "In16.Cu" signal "GND7")
		(2 "B.Cu" signal "BOTTOM")
		(9 "F.Adhes" user "F.Adhesive")
		(11 "B.Adhes" user "B.Adhesive")
		(13 "F.Paste" user "Package Geometry/Pastemask Top")
		(15 "B.Paste" user "Package Geometry/Pastemask Bottom")
		(5 "F.SilkS" user "Ref Des/Silkscreen Top")
		(7 "B.SilkS" user "Ref Des/Silkscreen Bottom")
		(1 "F.Mask" user "Board Geometry/Soldermask Top")
		(3 "B.Mask" user "Board Geometry/Soldermask Bottom")
		(17 "Dwgs.User" user "User.Drawings")
		(19 "Cmts.User" user "User.Comments")
		(21 "Eco1.User" user "User.Eco1")
		(23 "Eco2.User" user "User.Eco2")
		(25 "Edge.Cuts" user "Board Geometry/Outline")
		(27 "Margin" user)
		(31 "F.CrtYd" user "Package Geometry/Place Bound Top")
		(29 "B.CrtYd" user "Package Geometry/Place Bound Bottom")
		(35 "F.Fab" user "Ref Des/Assembly Top")
		(33 "B.Fab" user "Ref Des/Assembly Bottom")
	)
	(footprint ""
		(layer "F.Cu")
		(at 201.02068 -102.235)
		(property "Reference" "R4712"
			(at 0 0 0)
			(layer "F.SilkS")
			(hide yes)
			(effects
				(font
					(size 1.27 1.27)
				)
			)
		)
		(property "Value" ""
			(at 0 0 0)
			(layer "F.Fab")
			(effects
				(font
					(size 1.27 1.27)
				)
			)
		)
		(duplicate_pad_numbers_are_jumpers no)
		(fp_line
			(start -0.7874 -0.4064)
			(end 0.7874 -0.4064)
			(stroke
				(width 0.1524)
				(type default)
			)
			(layer "F.SilkS")
		)
		(fp_line
			(start -0.7874 0.4064)
			(end -0.7874 -0.4064)
			(stroke
				(width 0.1524)
				(type default)
			)
			(layer "F.SilkS")
		)
		(fp_line
			(start 0.7874 -0.4064)
			(end 0.7874 0.4064)
			(stroke
				(width 0.1524)
				(type default)
			)
			(layer "F.SilkS")
		)
		(fp_line
			(start 0.7874 0.4064)
			(end -0.7874 0.4064)
			(stroke
				(width 0.1524)
				(type default)
			)
			(layer "F.SilkS")
		)
		(fp_line
			(start -0.67945 -0.305054)
			(end -0.12065 -0.305054)
			(stroke
				(width 0.1)
				(type default)
			)
			(layer "F.Fab")
		)
		(fp_line
			(start -0.67945 0.3048)
			(end -0.67945 -0.305054)
			(stroke
				(width 0.1)
				(type default)
			)
			(layer "F.Fab")
		)
		(fp_line
			(start -0.12065 -0.305054)
			(end -0.12065 -0.2794)
			(stroke
				(width 0.1)
				(type default)
			)
			(layer "F.Fab")
		)
		(fp_line
			(start -0.12065 -0.2794)
			(end 0.12065 -0.2794)
			(stroke
				(width 0.1)
				(type default)
			)
			(layer "F.Fab")
		)
		(fp_line
			(start -0.12065 0.2794)
			(end -0.12065 0.3048)
			(stroke
				(width 0.1)
				(type default)
			)
			(layer "F.Fab")
		)
		(fp_line
			(start -0.12065 0.3048)
			(end -0.67945 0.3048)
			(stroke
				(width 0.1)
				(type default)
			)
			(layer "F.Fab")
		)
		(fp_line
			(start 0.120396 0.2794)
			(end -0.12065 0.2794)
			(stroke
				(width 0.1)
				(type default)
			)
			(layer "F.Fab")
		)
		(fp_line
			(start 0.120396 0.3048)
			(end 0.120396 0.2794)
			(stroke
				(width 0.1)
				(type default)
			)
			(layer "F.Fab")
		)
		(fp_line
			(start 0.12065 -0.3048)
			(end 0.67945 -0.3048)
			(stroke
				(width 0.1)
				(type default)
			)
			(layer "F.Fab")
		)
		(fp_line
			(start 0.12065 -0.2794)
			(end 0.12065 -0.3048)
			(stroke
				(width 0.1)
				(type default)
			)
			(layer "F.Fab")
		)
		(fp_line
			(start 0.67945 -0.3048)
			(end 0.67945 0.3048)
			(stroke
				(width 0.1)
				(type default)
			)
			(layer "F.Fab")
		)
		(fp_line
			(start 0.67945 0.3048)
			(end 0.120396 0.3048)
			(stroke
				(width 0.1)
				(type default)
			)
			(layer "F.Fab")
		)
		(pad "1" smd circle
			(at -0.40005 0)
			(size 0 0)
			(layers "F.Cu" "F.Mask" "F.Paste")
			(net "RST_PFR_OVR_RTC")
		)
		(pad "2" smd circle
			(at 0.40005 0)
			(size 0 0)
			(layers "F.Cu" "F.Mask" "F.Paste")
			(net "GND")
		)
	)
	(footprint ""
		(layer "F.Cu")
		(at 197.19036 -118.074948)
		(property "Reference" "R1469"
			(at 0 0 0)
			(layer "F.SilkS")
			(hide yes)
			(effects
				(font
					(size 1.27 1.27)
				)
			)
		)
		(property "Value" ""
			(at 0 0 0)
			(layer "F.Fab")
			(effects
				(font
					(size 1.27 1.27)
				)
			)
		)
		(duplicate_pad_numbers_are_jumpers no)
		(fp_line
			(start -0.7874 -0.4064)
			(end 0.7874 -0.4064)
			(stroke
				(width 0.1524)
				(type default)
			)
			(layer "F.SilkS")
		)
		(fp_line
			(start -0.7874 0.4064)
			(end -0.7874 -0.4064)
			(stroke
				(width 0.1524)
				(type default)
			)
			(layer "F.SilkS")
		)
		(fp_line
			(start 0.7874 -0.4064)
			(end 0.7874 0.4064)
			(stroke
				(width 0.1524)
				(type default)
			)
			(layer "F.SilkS")
		)
		(fp_line
			(start 0.7874 0.4064)
			(end -0.7874 0.4064)
			(stroke
				(width 0.1524)
				(type default)
			)
			(layer "F.SilkS")
		)
		(fp_line
			(start -0.67945 -0.305054)
			(end -0.12065 -0.305054)
			(stroke
				(width 0.1)
				(type default)
			)
			(layer "F.Fab")
		)
		(fp_line
			(start -0.67945 0.3048)
			(end -0.67945 -0.305054)
			(stroke
				(width 0.1)
				(type default)
			)
			(layer "F.Fab")
		)
		(fp_line
			(start -0.12065 -0.305054)
			(end -0.12065 -0.2794)
			(stroke
				(width 0.1)
				(type default)
			)
			(layer "F.Fab")
		)
		(fp_line
			(start -0.12065 -0.2794)
			(end 0.12065 -0.2794)
			(stroke
				(width 0.1)
				(type default)
			)
			(layer "F.Fab")
		)
		(fp_line
			(start -0.12065 0.2794)
			(end -0.12065 0.3048)
			(stroke
				(width 0.1)
				(type default)
			)
			(layer "F.Fab")
		)
		(fp_line
			(start -0.12065 0.3048)
			(end -0.67945 0.3048)
			(stroke
				(width 0.1)
				(type default)
			)
			(layer "F.Fab")
		)
		(fp_line
			(start 0.120396 0.2794)
			(end -0.12065 0.2794)
			(stroke
				(width 0.1)
				(type default)
			)
			(layer "F.Fab")
		)
		(fp_line
			(start 0.120396 0.3048)
			(end 0.120396 0.2794)
			(stroke
				(width 0.1)
				(type default)
			)
			(layer "F.Fab")
		)
		(fp_line
			(start 0.12065 -0.3048)
			(end 0.67945 -0.3048)
			(stroke
				(width 0.1)
				(type default)
			)
			(layer "F.Fab")
		)
		(fp_line
			(start 0.12065 -0.2794)
			(end 0.12065 -0.3048)
			(stroke
				(width 0.1)
				(type default)
			)
			(layer "F.Fab")
		)
		(fp_line
			(start 0.67945 -0.3048)
			(end 0.67945 0.3048)
			(stroke
				(width 0.1)
				(type default)
			)
			(layer "F.Fab")
		)
		(fp_line
			(start 0.67945 0.3048)
			(end 0.120396 0.3048)
			(stroke
				(width 0.1)
				(type default)
			)
			(layer "F.Fab")
		)
		(pad "1" smd circle
			(at -0.40005 0)
			(size 0 0)
			(layers "F.Cu" "F.Mask" "F.Paste")
			(net "RST_PLTRST_PLD_B_N")
		)
		(pad "2" smd circle
			(at 0.40005 0)
			(size 0 0)
			(layers "F.Cu" "F.Mask" "F.Paste")
			(net "RST_PLTRST_B_N")
		)
	)
)
